(kicad_pcb
	(version 20240108)
	(generator "pcbnew")
	(generator_version "8.0")
	(general
		(thickness 1.62)
		(legacy_teardrops no)
	)
	(paper "A4")
	(title_block
		(title "Jetson Orin Baseboard")
		(date "2025-03-12")
		(rev "1.3.4")
		(company "Antmicro Ltd")
		(comment 1 "www.antmicro.com")
		(comment 9 "footprints 121-124 of 677")
	)
	(layers
		(0 "F.Cu" signal)
		(1 "In1.Cu" signal)
		(2 "In2.Cu" signal)
		(3 "In3.Cu" signal)
		(4 "In4.Cu" jumper)
		(5 "In5.Cu" signal)
		(6 "In6.Cu" signal)
		(31 "B.Cu" signal)
		(32 "B.Adhes" user "B.Adhesive")
		(33 "F.Adhes" user "F.Adhesive")
		(34 "B.Paste" user)
		(35 "F.Paste" user)
		(36 "B.SilkS" user "B.Silkscreen")
		(37 "F.SilkS" user "F.Silkscreen")
		(38 "B.Mask" user)
		(39 "F.Mask" user)
		(40 "Dwgs.User" user "User.Drawings")
		(41 "Cmts.User" user "User.Comments")
		(42 "Eco1.User" user "User.Eco1")
		(43 "Eco2.User" user "User.Eco2")
		(44 "Edge.Cuts" user)
		(45 "Margin" user)
		(46 "B.CrtYd" user "B.Courtyard")
		(47 "F.CrtYd" user "F.Courtyard")
		(48 "B.Fab" user)
		(49 "F.Fab" user)
	)
	(footprint "antmicro-footprints:Conv_Murata_ULS-60W"
		(layer "F.Cu")
		(at 34.048 99.491145 90)
		(property "Reference" "U23"
			(at -3.558855 -1.523 180)
			(layer "F.SilkS")
			(effects
				(font
					(size 0.7 0.7)
					(thickness 0.15)
				)
				(justify left bottom)
			)
		)
		(property "Value" "ULS-12_5-D48N-C"
			(at -2.8 20.1 90)
			(layer "F.Fab")
			(effects
				(font
					(size 0.7 0.7)
					(thickness 0.15)
				)
				(justify left bottom)
			)
		)
		(property "Footprint" "antmicro-footprints:Conv_Murata_ULS-60W"
			(at 0 0 90)
			(layer "F.Fab")
			(hide yes)
			(effects
				(font
					(size 1.27 1.27)
					(thickness 0.15)
				)
			)
		)
		(property "Datasheet" "https://www.murata.com/products/productdata/8807040286750/uls.pdf?1649388617000"
			(at 0 0 90)
			(layer "F.Fab")
			(hide yes)
			(effects
				(font
					(size 1.27 1.27)
					(thickness 0.15)
				)
			)
		)
		(property "Description" "Isolated Through Hole DC/DC Converter, ITE, 2:1, 60 W, 1 Output, 12 V, 5 A"
			(at 0 0 90)
			(layer "F.Fab")
			(hide yes)
			(effects
				(font
					(size 1.27 1.27)
					(thickness 0.15)
				)
			)
		)
		(property "Manufacturer" "Murata"
			(at 0 0 90)
			(unlocked yes)
			(layer "F.Fab")
			(hide yes)
			(effects
				(font
					(size 1 1)
					(thickness 0.15)
				)
			)
		)
		(property "MPN" "ULS-12/5-D48N-C"
			(at 0 0 90)
			(unlocked yes)
			(layer "F.Fab")
			(hide yes)
			(effects
				(font
					(size 1 1)
					(thickness 0.15)
				)
			)
		)
		(property "Author" "Antmicro"
			(at 0 0 90)
			(unlocked yes)
			(layer "F.Fab")
			(hide yes)
			(effects
				(font
					(size 1 1)
					(thickness 0.15)
				)
			)
		)
		(property "License" "Apache-2.0"
			(at 0 0 90)
			(unlocked yes)
			(layer "F.Fab")
			(hide yes)
			(effects
				(font
					(size 1 1)
					(thickness 0.15)
				)
			)
		)
		(property "Alternatives 50W" " VCB4812SBO-50WR3, V36SE12004NRFA, PKU5513ESI, KHHD004A2B41Z"
			(at 0 0 90)
			(unlocked yes)
			(layer "F.Fab")
			(hide yes)
			(effects
				(font
					(size 1 1)
					(thickness 0.15)
				)
			)
		)
		(property "Alternatives 75W" " VCB4812SBO-75WR3"
			(at 0 0 90)
			(unlocked yes)
			(layer "F.Fab")
			(hide yes)
			(effects
				(font
					(size 1 1)
					(thickness 0.15)
				)
			)
		)
		(property "Alternatives 100W" "PKU4913DPIHS, VCB4812SBO-100WFR3"
			(at 0 0 90)
			(unlocked yes)
			(layer "F.Fab")
			(hide yes)
			(effects
				(font
					(size 1 1)
					(thickness 0.15)
				)
			)
		)
		(property "Alternatives 120W" "PQC50-48-S12-O"
			(at 0 0 90)
			(unlocked yes)
			(layer "F.Fab")
			(hide yes)
			(effects
				(font
					(size 1 1)
					(thickness 0.15)
				)
			)
		)
		(sheetname "Ethernet")
		(sheetfile "ethernet.kicad_sch")
		(attr through_hole)
		(fp_line
			(start 30.485 -3.807)
			(end -1.265 -3.807)
			(stroke
				(width 0.15)
				(type solid)
			)
			(layer "F.SilkS")
		)
		(fp_line
			(start -2.535 -2.537)
			(end -1.265 -3.807)
			(stroke
				(width 0.15)
				(type solid)
			)
			(layer "F.SilkS")
		)
		(fp_line
			(start 30.485 19.053)
			(end 30.485 -3.807)
			(stroke
				(width 0.15)
				(type solid)
			)
			(layer "F.SilkS")
		)
		(fp_line
			(start 30.485 19.053)
			(end -2.535 19.053)
			(stroke
				(width 0.15)
				(type solid)
			)
			(layer "F.SilkS")
		)
		(fp_line
			(start -2.535 19.053)
			(end -2.535 -2.537)
			(stroke
				(width 0.15)
				(type solid)
			)
			(layer "F.SilkS")
		)
		(fp_circle
			(center -1.9 0)
			(end -1.85 0)
			(stroke
				(width 0.15)
				(type solid)
			)
			(fill solid)
			(layer "F.SilkS")
		)
		(fp_rect
			(start -3.54 -4.81)
			(end 31.48 20.05)
			(stroke
				(width 0.05)
				(type solid)
			)
			(fill none)
			(layer "F.CrtYd")
		)
		(fp_line
			(start 30.485 -3.807)
			(end -1.265 -3.807)
			(stroke
				(width 0.15)
				(type solid)
			)
			(layer "F.Fab")
		)
		(fp_line
			(start -2.535 -2.537)
			(end -1.265 -3.807)
			(stroke
				(width 0.15)
				(type solid)
			)
			(layer "F.Fab")
		)
		(fp_line
			(start 30.485 19.053)
			(end 30.485 -3.807)
			(stroke
				(width 0.15)
				(type solid)
			)
			(layer "F.Fab")
		)
		(fp_line
			(start 30.485 19.053)
			(end -2.535 19.053)
			(stroke
				(width 0.15)
				(type solid)
			)
			(layer "F.Fab")
		)
		(fp_line
			(start -2.535 19.053)
			(end -2.535 -2.537)
			(stroke
				(width 0.15)
				(type solid)
			)
			(layer "F.Fab")
		)
		(fp_text user "License: Apache-2.0"
			(at -3.54 24.45 90)
			(layer "F.Fab")
			(hide yes)
			(effects
				(font
					(size 0.7 0.7)
					(thickness 0.15)
				)
				(justify left bottom)
			)
		)
		(fp_text user "${REFERENCE}"
			(at -3.54 23.25 90)
			(layer "F.Fab")
			(hide yes)
			(effects
				(font
					(size 0.7 0.7)
					(thickness 0.15)
				)
				(justify left bottom)
			)
		)
		(fp_text user "Author: Antmicro"
			(at -3.54 22.05 90)
			(layer "F.Fab")
			(hide yes)
			(effects
				(font
					(size 0.7 0.7)
					(thickness 0.15)
				)
				(justify left bottom)
			)
		)
		(pad "1" thru_hole rect
			(at 0 0 90)
			(size 2.54 2.54)
			(drill 1.4)
			(layers "*.Cu" "*.Mask")
			(remove_unused_layers no)
			(net 105 "/Ethernet/VDD")
			(pinfunction "VIN+")
			(pintype "power_in")
		)
		(pad "2" thru_hole circle
			(at 0 7.62 90)
			(size 2.54 2.54)
			(drill 1.4)
			(layers "*.Cu" "*.Mask")
			(remove_unused_layers no)
			(net 650 "/Ethernet/ULS-12_CTRL")
			(pinfunction "CTRL")
			(pintype "input")
		)
		(pad "3" thru_hole circle
			(at 0 15.24 90)
			(size 2.54 2.54)
			(drill 1.4)
			(layers "*.Cu" "*.Mask")
			(remove_unused_layers no)
			(net 106 "GNDD")
			(pinfunction "VIN-")
			(pintype "power_in")
		)
		(pad "4" thru_hole circle
			(at 27.94 15.24 90)
			(size 2.54 2.54)
			(drill 1.956)
			(layers "*.Cu" "*.Mask")
			(remove_unused_layers no)
			(net 1 "GND")
			(pinfunction "VOUT-")
			(pintype "power_out")
		)
		(pad "5" thru_hole circle
			(at 27.94 11.43 90)
			(size 2.54 2.54)
			(drill 1.4)
			(layers "*.Cu" "*.Mask")
			(remove_unused_layers no)
			(net 1 "GND")
			(pinfunction "SENSE-")
			(pintype "passive")
		)
		(pad "6" thru_hole circle
			(at 27.94 7.62 90)
			(size 2.54 2.54)
			(drill 1.4)
			(layers "*.Cu" "*.Mask")
			(remove_unused_layers no)
			(net 683 "Net-(U23-TRIM)")
			(pinfunction "TRIM")
			(pintype "input")
		)
		(pad "7" thru_hole circle
			(at 27.94 3.81 90)
			(size 2.54 2.54)
			(drill 1.4)
			(layers "*.Cu" "*.Mask")
			(remove_unused_layers no)
			(net 500 "POE_OUTPUT")
			(pinfunction "SENSE+")
			(pintype "passive")
		)
		(pad "8" thru_hole circle
			(at 27.94 0 90)
			(size 2.54 2.54)
			(drill 1.956)
			(layers "*.Cu" "*.Mask")
			(remove_unused_layers no)
			(net 500 "POE_OUTPUT")
			(pinfunction "VOUT+")
			(pintype "power_out")
		)
	)
	(footprint "antmicro-footprints:C_0402_1005Metric"
		(layer "F.Cu")
		(at 75.6 110.967469 -90)
		(descr "Capacitor SMD 0402")
		(tags "capacitor SMD 0402")
		(property "Reference" "C63"
			(at 2.982531 -0.45 -90)
			(layer "F.SilkS")
			(effects
				(font
					(size 0.7 0.7)
					(thickness 0.15)
				)
				(justify left bottom)
			)
		)
		(property "Value" "C_100n_0402"
			(at 0 1.4 -90)
			(layer "F.Fab")
			(effects
				(font
					(size 0.7 0.7)
					(thickness 0.15)
				)
				(justify left bottom)
			)
		)
		(property "Footprint" "antmicro-footprints:C_0402_1005Metric"
			(at 0 0 -90)
			(layer "F.Fab")
			(hide yes)
			(effects
				(font
					(size 1.27 1.27)
					(thickness 0.15)
				)
			)
		)
		(property "Datasheet" "https://www.murata.com/products/productdetail?partno=GRM155R61H104KE14%23"
			(at 0 0 -90)
			(layer "F.Fab")
			(hide yes)
			(effects
				(font
					(size 1.27 1.27)
					(thickness 0.15)
				)
			)
		)
		(property "Author" "Antmicro"
			(at -35.367469 186.567469 0)
			(layer "F.Fab")
			(hide yes)
			(effects
				(font
					(size 1 1)
					(thickness 0.15)
				)
			)
		)
		(property "Dielectric" "X5R"
			(at -35.367469 186.567469 0)
			(layer "F.Fab")
			(hide yes)
			(effects
				(font
					(size 1 1)
					(thickness 0.15)
				)
			)
		)
		(property "License" "Apache-2.0"
			(at -35.367469 186.567469 0)
			(layer "F.Fab")
			(hide yes)
			(effects
				(font
					(size 1 1)
					(thickness 0.15)
				)
			)
		)
		(property "MPN" "GRM155R61H104KE14D"
			(at -35.367469 186.567469 0)
			(layer "F.Fab")
			(hide yes)
			(effects
				(font
					(size 1 1)
					(thickness 0.15)
				)
			)
		)
		(property "Manufacturer" "Murata"
			(at -35.367469 186.567469 0)
			(layer "F.Fab")
			(hide yes)
			(effects
				(font
					(size 1 1)
					(thickness 0.15)
				)
			)
		)
		(property "Val" "100n"
			(at -35.367469 186.567469 0)
			(layer "F.Fab")
			(hide yes)
			(effects
				(font
					(size 1 1)
					(thickness 0.15)
				)
			)
		)
		(property "Voltage" "50V"
			(at -35.367469 186.567469 0)
			(layer "F.Fab")
			(hide yes)
			(effects
				(font
					(size 1 1)
					(thickness 0.15)
				)
			)
		)
		(sheetname "USB Debug, DP")
		(sheetfile "usb.kicad_sch")
		(attr smd)
		(fp_rect
			(start -0.925 -0.47)
			(end 0.925 0.47)
			(stroke
				(width 0.05)
				(type default)
			)
			(fill none)
			(layer "F.CrtYd")
		)
		(fp_line
			(start -0.494 0.248)
			(end -0.494 -0.25)
			(stroke
				(width 0.15)
				(type solid)
			)
			(layer "F.Fab")
		)
		(fp_line
			(start 0.504 0.248)
			(end -0.494 0.248)
			(stroke
				(width 0.15)
				(type solid)
			)
			(layer "F.Fab")
		)
		(fp_line
			(start -0.494 -0.25)
			(end 0.504 -0.25)
			(stroke
				(width 0.15)
				(type solid)
			)
			(layer "F.Fab")
		)
		(fp_line
			(start 0.504 -0.25)
			(end 0.504 0.248)
			(stroke
				(width 0.15)
				(type solid)
			)
			(layer "F.Fab")
		)
		(fp_text user "Author: Antmicro"
			(at -0.932 4.17 -90)
			(layer "F.Fab")
			(hide yes)
			(effects
				(font
					(size 0.7 0.7)
					(thickness 0.15)
				)
				(justify left bottom)
			)
		)
		(fp_text user "${REFERENCE}"
			(at -0.932 3.168 -90)
			(layer "F.Fab")
			(hide yes)
			(effects
				(font
					(size 0.7 0.7)
					(thickness 0.15)
				)
				(justify left bottom)
			)
		)
		(fp_text user "License: Apache-2.0"
			(at -0.932 5.17 -90)
			(layer "F.Fab")
			(hide yes)
			(effects
				(font
					(size 0.7 0.7)
					(thickness 0.15)
				)
				(justify left bottom)
			)
		)
		(pad "1" smd roundrect
			(at -0.48 0 270)
			(size 0.59 0.64)
			(layers "F.Cu" "F.Paste" "F.Mask")
			(roundrect_rratio 0.25)
			(net 200 "/USB Debug, DP/USBC0_TX2_N")
			(pintype "passive")
		)
		(pad "2" smd roundrect
			(at 0.48 0 270)
			(size 0.59 0.64)
			(layers "F.Cu" "F.Paste" "F.Mask")
			(roundrect_rratio 0.25)
			(net 201 "/USB Debug, DP/USBC0_CONN_TX2_N")
			(pintype "passive")
		)
	)
	(footprint "antmicro-footprints:R_0402_1005Metric"
		(layer "F.Cu")
		(at 134.85 112.3 -90)
		(descr "Resistor SMD 0402")
		(tags "resistor SMD 0402")
		(property "Reference" "R66"
			(at 1.15 3.27 -90)
			(layer "F.SilkS")
			(effects
				(font
					(size 0.7 0.7)
					(thickness 0.15)
				)
				(justify left bottom)
			)
		)
		(property "Value" "R_10k_0402"
			(at 0 1.4 -90)
			(layer "F.Fab")
			(effects
				(font
					(size 0.7 0.7)
					(thickness 0.15)
				)
				(justify left bottom)
			)
		)
		(property "Footprint" "antmicro-footprints:R_0402_1005Metric"
			(at 0 0 -90)
			(layer "F.Fab")
			(hide yes)
			(effects
				(font
					(size 1.27 1.27)
					(thickness 0.15)
				)
			)
		)
		(property "Datasheet" "https://www.bourns.com/docs/product-datasheets/cr.pdf"
			(at 0 0 -90)
			(layer "F.Fab")
			(hide yes)
			(effects
				(font
					(size 1.27 1.27)
					(thickness 0.15)
				)
			)
		)
		(property "Author" "Antmicro"
			(at 22.55 247.15 0)
			(layer "F.Fab")
			(hide yes)
			(effects
				(font
					(size 1 1)
					(thickness 0.15)
				)
			)
		)
		(property "License" "Apache-2.0"
			(at 22.55 247.15 0)
			(layer "F.Fab")
			(hide yes)
			(effects
				(font
					(size 1 1)
					(thickness 0.15)
				)
			)
		)
		(property "MPN" "CR0402-FX-1002GLF"
			(at 22.55 247.15 0)
			(layer "F.Fab")
			(hide yes)
			(effects
				(font
					(size 1 1)
					(thickness 0.15)
				)
			)
		)
		(property "Manufacturer" "Bourns"
			(at 22.55 247.15 0)
			(layer "F.Fab")
			(hide yes)
			(effects
				(font
					(size 1 1)
					(thickness 0.15)
				)
			)
		)
		(property "Tolerance" "1%"
			(at 22.55 247.15 0)
			(layer "F.Fab")
			(hide yes)
			(effects
				(font
					(size 1 1)
					(thickness 0.15)
				)
			)
		)
		(property "Val" "10k"
			(at 22.55 247.15 0)
			(layer "F.Fab")
			(hide yes)
			(effects
				(font
					(size 1 1)
					(thickness 0.15)
				)
			)
		)
		(sheetname "CSI")
		(sheetfile "csi.kicad_sch")
		(attr smd)
		(fp_rect
			(start -0.925 -0.47)
			(end 0.925 0.47)
			(stroke
				(width 0.05)
				(type default)
			)
			(fill none)
			(layer "F.CrtYd")
		)
		(fp_rect
			(start -0.5 -0.25)
			(end 0.5 0.25)
			(stroke
				(width 0.15)
				(type solid)
			)
			(fill none)
			(layer "F.Fab")
		)
		(fp_text user "License: Apache-2.0"
			(at -0.95 5.169 -90)
			(layer "F.Fab")
			(hide yes)
			(effects
				(font
					(size 0.7 0.7)
					(thickness 0.15)
				)
				(justify left bottom)
			)
		)
		(fp_text user "Author: Antmicro"
			(at -0.95 4.169 -90)
			(layer "F.Fab")
			(hide yes)
			(effects
				(font
					(size 0.7 0.7)
					(thickness 0.15)
				)
				(justify left bottom)
			)
		)
		(fp_text user "${REFERENCE}"
			(at -0.95 3.168 -90)
			(layer "F.Fab")
			(hide yes)
			(effects
				(font
					(size 0.7 0.7)
					(thickness 0.15)
				)
				(justify left bottom)
			)
		)
		(pad "1" smd roundrect
			(at -0.48 0 270)
			(size 0.59 0.64)
			(layers "F.Cu" "F.Paste" "F.Mask")
			(roundrect_rratio 0.25)
			(net 87 "+3V3")
			(pintype "passive")
		)
		(pad "2" smd roundrect
			(at 0.48 0 270)
			(size 0.59 0.64)
			(layers "F.Cu" "F.Paste" "F.Mask")
			(roundrect_rratio 0.25)
			(net 311 "CSIA_FLG")
			(pintype "passive")
		)
	)
	(footprint "antmicro-footprints:SOD-523"
		(layer "F.Cu")
		(at 83.71 122.4)
		(property "Reference" "D63"
			(at -1.01 -0.59 0)
			(layer "F.SilkS")
			(effects
				(font
					(size 0.7 0.7)
					(thickness 0.15)
				)
				(justify left bottom)
			)
		)
		(property "Value" "RB521S30T1G"
			(at 0 1.499 0)
			(layer "F.Fab")
			(effects
				(font
					(size 0.7 0.7)
					(thickness 0.15)
				)
				(justify left bottom)
			)
		)
		(property "Footprint" "antmicro-footprints:SOD-523"
			(at 0 0 0)
			(layer "F.Fab")
			(hide yes)
			(effects
				(font
					(size 1.27 1.27)
					(thickness 0.15)
				)
			)
		)
		(property "Datasheet" "https://www.onsemi.com/pdf/datasheet/rb521s30t1-d.pdf"
			(at 0 0 0)
			(layer "F.Fab")
			(hide yes)
			(effects
				(font
					(size 1.27 1.27)
					(thickness 0.15)
				)
			)
		)
		(property "Author" "Antmicro"
			(at 0 0 0)
			(layer "F.Fab")
			(hide yes)
			(effects
				(font
					(size 1 1)
					(thickness 0.15)
				)
			)
		)
		(property "License" "Apache-2.0"
			(at 0 0 0)
			(layer "F.Fab")
			(hide yes)
			(effects
				(font
					(size 1 1)
					(thickness 0.15)
				)
			)
		)
		(property "MPN" "RB521S30T1G"
			(at 0 0 0)
			(layer "F.Fab")
			(hide yes)
			(effects
				(font
					(size 1 1)
					(thickness 0.15)
				)
			)
		)
		(property "Manufacturer" "ON Semiconductor"
			(at 0 0 0)
			(layer "F.Fab")
			(hide yes)
			(effects
				(font
					(size 1 1)
					(thickness 0.15)
				)
			)
		)
		(sheetname "Peripherals")
		(sheetfile "peripherals.kicad_sch")
		(attr smd)
		(fp_line
			(start -0.35 -0.5)
			(end -0.35 0.5)
			(stroke
				(width 0.15)
				(type solid)
			)
			(layer "F.SilkS")
		)
		(fp_rect
			(start -1 -0.6)
			(end 1 0.6)
			(stroke
				(width 0.05)
				(type solid)
			)
			(fill none)
			(layer "F.CrtYd")
		)
		(fp_line
			(start -0.652 -0.425)
			(end 0.65 -0.425)
			(stroke
				(width 0.15)
				(type solid)
			)
			(layer "F.Fab")
		)
		(fp_line
			(start -0.652 0.423)
			(end -0.652 -0.425)
			(stroke
				(width 0.15)
				(type solid)
			)
			(layer "F.Fab")
		)
		(fp_line
			(start -0.652 0.423)
			(end 0.65 0.423)
			(stroke
				(width 0.15)
				(type solid)
			)
			(layer "F.Fab")
		)
		(fp_line
			(start -0.35 -0.4)
			(end -0.35 0.4)
			(stroke
				(width 0.15)
				(type solid)
			)
			(layer "F.Fab")
		)
		(fp_line
			(start 0.65 -0.425)
			(end 0.65 0.423)
			(stroke
				(width 0.15)
				(type solid)
			)
			(layer "F.Fab")
		)
		(fp_text user "Author: Antmicro"
			(at -1.276 4.7 0)
			(layer "F.Fab")
			(hide yes)
			(effects
				(font
					(size 0.7 0.7)
					(thickness 0.15)
				)
				(justify left bottom)
			)
		)
		(fp_text user "${REFERENCE}"
			(at -1.276 3.499 0)
			(layer "F.Fab")
			(hide yes)
			(effects
				(font
					(size 0.7 0.7)
					(thickness 0.15)
				)
				(justify left bottom)
			)
		)
		(fp_text user "License: Apache-2.0"
			(at -1.276 5.9 0)
			(layer "F.Fab")
			(hide yes)
			(effects
				(font
					(size 0.7 0.7)
					(thickness 0.15)
				)
				(justify left bottom)
			)
		)
		(pad "1" smd roundrect
			(at -0.701 0)
			(size 0.5 0.6)
			(layers "F.Cu" "F.Paste" "F.Mask")
			(roundrect_rratio 0.25)
			(net 671 "/Peripherals/SCK")
			(pinfunction "C")
			(pintype "passive")
		)
		(pad "2" smd roundrect
			(at 0.699 0)
			(size 0.5 0.6)
			(layers "F.Cu" "F.Paste" "F.Mask")
			(roundrect_rratio 0.25)
			(net 779 "Net-(D63-A)")
			(pinfunction "A")
			(pintype "passive")
		)
	)
)
